(kicad_pcb
	(version 20260206)
	(generator "pcbnew")
	(generator_version "10.0")
	(general
		(thickness 1.6)
		(legacy_teardrops no)
	)
	(paper "A4")
	(title_block
		(title "04192023_DAF0TMB3IC0_F0TG_MB_C_brd_V02_OCP.brd")
		(comment 1 "Grand Teton / footprints 7302-7307 of 8354")
	)
	(layers
		(0 "F.Cu" signal "TOP")
		(4 "In1.Cu" signal "GND")
		(6 "In2.Cu" signal "IN1")
		(8 "In3.Cu" signal "GND1")
		(10 "In4.Cu" signal "IN2")
		(12 "In5.Cu" signal "GND2")
		(14 "In6.Cu" signal "IN3")
		(16 "In7.Cu" signal "GND3")
		(18 "In8.Cu" signal "VCC")
		(20 "In9.Cu" signal "VCC1")
		(22 "In10.Cu" signal "GND4")
		(24 "In11.Cu" signal "IN4")
		(26 "In12.Cu" signal "GND5")
		(28 "In13.Cu" signal "IN5")
		(30 "In14.Cu" signal "GND6")
		(32 "In15.Cu" signal "IN6")
		(34 "In16.Cu" signal "GND7")
		(2 "B.Cu" signal "BOTTOM")
		(9 "F.Adhes" user "F.Adhesive")
		(11 "B.Adhes" user "B.Adhesive")
		(13 "F.Paste" user "Package Geometry/Pastemask Top")
		(15 "B.Paste" user "Package Geometry/Pastemask Bottom")
		(5 "F.SilkS" user "Ref Des/Silkscreen Top")
		(7 "B.SilkS" user "Ref Des/Silkscreen Bottom")
		(1 "F.Mask" user "Board Geometry/Soldermask Top")
		(3 "B.Mask" user "Board Geometry/Soldermask Bottom")
		(17 "Dwgs.User" user "User.Drawings")
		(19 "Cmts.User" user "User.Comments")
		(21 "Eco1.User" user "User.Eco1")
		(23 "Eco2.User" user "User.Eco2")
		(25 "Edge.Cuts" user "Board Geometry/Outline")
		(27 "Margin" user)
		(31 "F.CrtYd" user "Package Geometry/Place Bound Top")
		(29 "B.CrtYd" user "Package Geometry/Place Bound Bottom")
		(35 "F.Fab" user "Ref Des/Assembly Top")
		(33 "B.Fab" user "Ref Des/Assembly Bottom")
	)
	(footprint ""
		(layer "B.Cu")
		(at 111.379 -418.211 180)
		(property "Reference" "R3503"
			(at 0 0 0)
			(layer "B.SilkS")
			(hide yes)
			(effects
				(font
					(size 1.27 1.27)
				)
				(justify mirror)
			)
		)
		(property "Value" ""
			(at 0 0 0)
			(layer "B.Fab")
			(effects
				(font
					(size 1.27 1.27)
				)
				(justify mirror)
			)
		)
		(duplicate_pad_numbers_are_jumpers no)
		(fp_line
			(start 0.7874 0.4064)
			(end 0.7874 -0.4064)
			(stroke
				(width 0.1524)
				(type default)
			)
			(layer "B.SilkS")
		)
		(fp_line
			(start 0.7874 -0.4064)
			(end -0.7874 -0.4064)
			(stroke
				(width 0.1524)
				(type default)
			)
			(layer "B.SilkS")
		)
		(fp_line
			(start -0.7874 0.4064)
			(end 0.7874 0.4064)
			(stroke
				(width 0.1524)
				(type default)
			)
			(layer "B.SilkS")
		)
		(fp_line
			(start -0.7874 -0.4064)
			(end -0.7874 0.4064)
			(stroke
				(width 0.1524)
				(type default)
			)
			(layer "B.SilkS")
		)
		(fp_line
			(start 0.67945 0.3048)
			(end 0.67945 -0.305054)
			(stroke
				(width 0.1)
				(type default)
			)
			(layer "B.Fab")
		)
		(fp_line
			(start 0.67945 -0.305054)
			(end 0.12065 -0.305054)
			(stroke
				(width 0.1)
				(type default)
			)
			(layer "B.Fab")
		)
		(fp_line
			(start 0.12065 0.3048)
			(end 0.67945 0.3048)
			(stroke
				(width 0.1)
				(type default)
			)
			(layer "B.Fab")
		)
		(fp_line
			(start 0.12065 0.2794)
			(end 0.12065 0.3048)
			(stroke
				(width 0.1)
				(type default)
			)
			(layer "B.Fab")
		)
		(fp_line
			(start 0.12065 -0.2794)
			(end -0.12065 -0.2794)
			(stroke
				(width 0.1)
				(type default)
			)
			(layer "B.Fab")
		)
		(fp_line
			(start 0.12065 -0.305054)
			(end 0.12065 -0.2794)
			(stroke
				(width 0.1)
				(type default)
			)
			(layer "B.Fab")
		)
		(fp_line
			(start -0.120396 0.3048)
			(end -0.120396 0.2794)
			(stroke
				(width 0.1)
				(type default)
			)
			(layer "B.Fab")
		)
		(fp_line
			(start -0.120396 0.2794)
			(end 0.12065 0.2794)
			(stroke
				(width 0.1)
				(type default)
			)
			(layer "B.Fab")
		)
		(fp_line
			(start -0.12065 -0.2794)
			(end -0.12065 -0.3048)
			(stroke
				(width 0.1)
				(type default)
			)
			(layer "B.Fab")
		)
		(fp_line
			(start -0.12065 -0.3048)
			(end -0.67945 -0.3048)
			(stroke
				(width 0.1)
				(type default)
			)
			(layer "B.Fab")
		)
		(fp_line
			(start -0.67945 0.3048)
			(end -0.120396 0.3048)
			(stroke
				(width 0.1)
				(type default)
			)
			(layer "B.Fab")
		)
		(fp_line
			(start -0.67945 -0.3048)
			(end -0.67945 0.3048)
			(stroke
				(width 0.1)
				(type default)
			)
			(layer "B.Fab")
		)
		(pad "1" smd circle
			(at 0.40005 0)
			(size 0 0)
			(layers "B.Cu" "B.Mask" "B.Paste")
			(net "P3V3_AUX")
		)
		(pad "2" smd circle
			(at -0.40005 0)
			(size 0 0)
			(layers "B.Cu" "B.Mask" "B.Paste")
			(net "GPU_FPGA_EROT_FATALERR")
		)
	)
	(footprint ""
		(layer "B.Cu")
		(at 230.505 -242.443 90)
		(property "Reference" "R323"
			(at 0 0 90)
			(layer "B.SilkS")
			(hide yes)
			(effects
				(font
					(size 1.27 1.27)
				)
				(justify mirror)
			)
		)
		(property "Value" ""
			(at 0 0 90)
			(layer "B.Fab")
			(effects
				(font
					(size 1.27 1.27)
				)
				(justify mirror)
			)
		)
		(duplicate_pad_numbers_are_jumpers no)
		(fp_line
			(start 0.7874 -0.4064)
			(end -0.7874 -0.4064)
			(stroke
				(width 0.1524)
				(type default)
			)
			(layer "B.SilkS")
		)
		(fp_line
			(start -0.7874 -0.4064)
			(end -0.7874 0.4064)
			(stroke
				(width 0.1524)
				(type default)
			)
			(layer "B.SilkS")
		)
		(fp_line
			(start 0.7874 0.4064)
			(end 0.7874 -0.4064)
			(stroke
				(width 0.1524)
				(type default)
			)
			(layer "B.SilkS")
		)
		(fp_line
			(start -0.7874 0.4064)
			(end 0.7874 0.4064)
			(stroke
				(width 0.1524)
				(type default)
			)
			(layer "B.SilkS")
		)
		(fp_line
			(start 0.67945 -0.305054)
			(end 0.12065 -0.305054)
			(stroke
				(width 0.1)
				(type default)
			)
			(layer "B.Fab")
		)
		(fp_line
			(start 0.12065 -0.305054)
			(end 0.12065 -0.2794)
			(stroke
				(width 0.1)
				(type default)
			)
			(layer "B.Fab")
		)
		(fp_line
			(start -0.12065 -0.3048)
			(end -0.67945 -0.3048)
			(stroke
				(width 0.1)
				(type default)
			)
			(layer "B.Fab")
		)
		(fp_line
			(start -0.67945 -0.3048)
			(end -0.67945 0.3048)
			(stroke
				(width 0.1)
				(type default)
			)
			(layer "B.Fab")
		)
		(fp_line
			(start 0.12065 -0.2794)
			(end -0.12065 -0.2794)
			(stroke
				(width 0.1)
				(type default)
			)
			(layer "B.Fab")
		)
		(fp_line
			(start -0.12065 -0.2794)
			(end -0.12065 -0.3048)
			(stroke
				(width 0.1)
				(type default)
			)
			(layer "B.Fab")
		)
		(fp_line
			(start 0.12065 0.2794)
			(end 0.12065 0.3048)
			(stroke
				(width 0.1)
				(type default)
			)
			(layer "B.Fab")
		)
		(fp_line
			(start -0.120396 0.2794)
			(end 0.12065 0.2794)
			(stroke
				(width 0.1)
				(type default)
			)
			(layer "B.Fab")
		)
		(fp_line
			(start 0.67945 0.3048)
			(end 0.67945 -0.305054)
			(stroke
				(width 0.1)
				(type default)
			)
			(layer "B.Fab")
		)
		(fp_line
			(start 0.12065 0.3048)
			(end 0.67945 0.3048)
			(stroke
				(width 0.1)
				(type default)
			)
			(layer "B.Fab")
		)
		(fp_line
			(start -0.120396 0.3048)
			(end -0.120396 0.2794)
			(stroke
				(width 0.1)
				(type default)
			)
			(layer "B.Fab")
		)
		(fp_line
			(start -0.67945 0.3048)
			(end -0.120396 0.3048)
			(stroke
				(width 0.1)
				(type default)
			)
			(layer "B.Fab")
		)
		(pad "1" smd rect
			(at 0.40005 0 90)
			(size 0.4572 0.508)
			(layers "B.Cu" "B.Mask" "B.Paste")
			(net "SMB_CPU0_CPU1_APML_SDA_R2")
		)
		(pad "2" smd rect
			(at -0.40005 0 90)
			(size 0.4572 0.508)
			(layers "B.Cu" "B.Mask" "B.Paste")
			(net "SMB_CPU0_CPU1_APML_MUX1_SDA")
		)
	)
	(footprint ""
		(layer "B.Cu")
		(at 402.322538 -321.179952 180)
		(property "Reference" "R446"
			(at 0 0 0)
			(layer "B.SilkS")
			(hide yes)
			(effects
				(font
					(size 1.27 1.27)
				)
				(justify mirror)
			)
		)
		(property "Value" ""
			(at 0 0 0)
			(layer "B.Fab")
			(effects
				(font
					(size 1.27 1.27)
				)
				(justify mirror)
			)
		)
		(duplicate_pad_numbers_are_jumpers no)
		(fp_line
			(start 0.7874 0.4064)
			(end 0.7874 -0.4064)
			(stroke
				(width 0.1524)
				(type default)
			)
			(layer "B.SilkS")
		)
		(fp_line
			(start 0.7874 -0.4064)
			(end -0.7874 -0.4064)
			(stroke
				(width 0.1524)
				(type default)
			)
			(layer "B.SilkS")
		)
		(fp_line
			(start -0.7874 0.4064)
			(end 0.7874 0.4064)
			(stroke
				(width 0.1524)
				(type default)
			)
			(layer "B.SilkS")
		)
		(fp_line
			(start -0.7874 -0.4064)
			(end -0.7874 0.4064)
			(stroke
				(width 0.1524)
				(type default)
			)
			(layer "B.SilkS")
		)
		(fp_line
			(start 0.67945 0.3048)
			(end 0.67945 -0.305054)
			(stroke
				(width 0.1)
				(type default)
			)
			(layer "B.Fab")
		)
		(fp_line
			(start 0.67945 -0.305054)
			(end 0.12065 -0.305054)
			(stroke
				(width 0.1)
				(type default)
			)
			(layer "B.Fab")
		)
		(fp_line
			(start 0.12065 0.3048)
			(end 0.67945 0.3048)
			(stroke
				(width 0.1)
				(type default)
			)
			(layer "B.Fab")
		)
		(fp_line
			(start 0.12065 0.2794)
			(end 0.12065 0.3048)
			(stroke
				(width 0.1)
				(type default)
			)
			(layer "B.Fab")
		)
		(fp_line
			(start 0.12065 -0.2794)
			(end -0.12065 -0.2794)
			(stroke
				(width 0.1)
				(type default)
			)
			(layer "B.Fab")
		)
		(fp_line
			(start 0.12065 -0.305054)
			(end 0.12065 -0.2794)
			(stroke
				(width 0.1)
				(type default)
			)
			(layer "B.Fab")
		)
		(fp_line
			(start -0.120396 0.3048)
			(end -0.120396 0.2794)
			(stroke
				(width 0.1)
				(type default)
			)
			(layer "B.Fab")
		)
		(fp_line
			(start -0.120396 0.2794)
			(end 0.12065 0.2794)
			(stroke
				(width 0.1)
				(type default)
			)
			(layer "B.Fab")
		)
		(fp_line
			(start -0.12065 -0.2794)
			(end -0.12065 -0.3048)
			(stroke
				(width 0.1)
				(type default)
			)
			(layer "B.Fab")
		)
		(fp_line
			(start -0.12065 -0.3048)
			(end -0.67945 -0.3048)
			(stroke
				(width 0.1)
				(type default)
			)
			(layer "B.Fab")
		)
		(fp_line
			(start -0.67945 0.3048)
			(end -0.120396 0.3048)
			(stroke
				(width 0.1)
				(type default)
			)
			(layer "B.Fab")
		)
		(fp_line
			(start -0.67945 -0.3048)
			(end -0.67945 0.3048)
			(stroke
				(width 0.1)
				(type default)
			)
			(layer "B.Fab")
		)
		(pad "1" smd circle
			(at 0.40005 0)
			(size 0 0)
			(layers "B.Cu" "B.Mask" "B.Paste")
			(net "IRQ_SMI_ACTIVE_N")
		)
		(pad "2" smd circle
			(at -0.40005 0)
			(size 0 0)
			(layers "B.Cu" "B.Mask" "B.Paste")
			(net "PVDD18_S5_P0")
		)
	)
	(footprint ""
		(layer "B.Cu")
		(at 243.713 -322.834)
		(property "Reference" "C1082"
			(at 0 0 0)
			(layer "B.SilkS")
			(hide yes)
			(effects
				(font
					(size 1.27 1.27)
				)
				(justify mirror)
			)
		)
		(property "Value" ""
			(at 0 0 0)
			(layer "B.Fab")
			(effects
				(font
					(size 1.27 1.27)
				)
				(justify mirror)
			)
		)
		(duplicate_pad_numbers_are_jumpers no)
		(fp_line
			(start -0.7874 -0.4064)
			(end -0.7874 0.4064)
			(stroke
				(width 0.1524)
				(type default)
			)
			(layer "B.SilkS")
		)
		(fp_line
			(start -0.7874 0.4064)
			(end 0.7874 0.4064)
			(stroke
				(width 0.1524)
				(type default)
			)
			(layer "B.SilkS")
		)
		(fp_line
			(start 0.7874 -0.4064)
			(end -0.7874 -0.4064)
			(stroke
				(width 0.1524)
				(type default)
			)
			(layer "B.SilkS")
		)
		(fp_line
			(start 0.7874 0.4064)
			(end 0.7874 -0.4064)
			(stroke
				(width 0.1524)
				(type default)
			)
			(layer "B.SilkS")
		)
		(fp_line
			(start -0.67945 -0.3048)
			(end -0.67945 0.3048)
			(stroke
				(width 0.1)
				(type default)
			)
			(layer "B.Fab")
		)
		(fp_line
			(start -0.67945 0.3048)
			(end -0.120396 0.3048)
			(stroke
				(width 0.1)
				(type default)
			)
			(layer "B.Fab")
		)
		(fp_line
			(start -0.12065 -0.3048)
			(end -0.67945 -0.3048)
			(stroke
				(width 0.1)
				(type default)
			)
			(layer "B.Fab")
		)
		(fp_line
			(start -0.12065 -0.2794)
			(end -0.12065 -0.3048)
			(stroke
				(width 0.1)
				(type default)
			)
			(layer "B.Fab")
		)
		(fp_line
			(start -0.120396 0.2794)
			(end 0.12065 0.2794)
			(stroke
				(width 0.1)
				(type default)
			)
			(layer "B.Fab")
		)
		(fp_line
			(start -0.120396 0.3048)
			(end -0.120396 0.2794)
			(stroke
				(width 0.1)
				(type default)
			)
			(layer "B.Fab")
		)
		(fp_line
			(start 0.12065 -0.305054)
			(end 0.12065 -0.2794)
			(stroke
				(width 0.1)
				(type default)
			)
			(layer "B.Fab")
		)
		(fp_line
			(start 0.12065 -0.2794)
			(end -0.12065 -0.2794)
			(stroke
				(width 0.1)
				(type default)
			)
			(layer "B.Fab")
		)
		(fp_line
			(start 0.12065 0.2794)
			(end 0.12065 0.3048)
			(stroke
				(width 0.1)
				(type default)
			)
			(layer "B.Fab")
		)
		(fp_line
			(start 0.12065 0.3048)
			(end 0.67945 0.3048)
			(stroke
				(width 0.1)
				(type default)
			)
			(layer "B.Fab")
		)
		(fp_line
			(start 0.67945 -0.305054)
			(end 0.12065 -0.305054)
			(stroke
				(width 0.1)
				(type default)
			)
			(layer "B.Fab")
		)
		(fp_line
			(start 0.67945 0.3048)
			(end 0.67945 -0.305054)
			(stroke
				(width 0.1)
				(type default)
			)
			(layer "B.Fab")
		)
		(pad "1" smd circle
			(at 0.40005 0 180)
			(size 0 0)
			(layers "B.Cu" "B.Mask" "B.Paste")
			(net "PVDD_33_S5_ADC_MAM")
		)
		(pad "2" smd circle
			(at -0.40005 0 180)
			(size 0 0)
			(layers "B.Cu" "B.Mask" "B.Paste")
			(net "GND")
		)
	)
	(footprint ""
		(layer "B.Cu")
		(at 308.318154 -396.393162 -90)
		(property "Reference" "C538"
			(at 0 0 90)
			(layer "B.SilkS")
			(hide yes)
			(effects
				(font
					(size 1.27 1.27)
				)
				(justify mirror)
			)
		)
		(property "Value" ""
			(at 0 0 90)
			(layer "B.Fab")
			(effects
				(font
					(size 1.27 1.27)
				)
				(justify mirror)
			)
		)
		(duplicate_pad_numbers_are_jumpers no)
		(fp_line
			(start -0.299974 0.150114)
			(end 0.299974 0.150114)
			(stroke
				(width 0.1)
				(type default)
			)
			(layer "B.Fab")
		)
		(fp_line
			(start 0.299974 0.150114)
			(end 0.299974 -0.150114)
			(stroke
				(width 0.1)
				(type default)
			)
			(layer "B.Fab")
		)
		(fp_line
			(start -0.299974 -0.150114)
			(end -0.299974 0.150114)
			(stroke
				(width 0.1)
				(type default)
			)
			(layer "B.Fab")
		)
		(fp_line
			(start 0.299974 -0.150114)
			(end -0.299974 -0.150114)
			(stroke
				(width 0.1)
				(type default)
			)
			(layer "B.Fab")
		)
		(pad "1" smd rect
			(at 0.2667 0 90)
			(size 0.3048 0.381)
			(layers "B.Cu" "B.Mask" "B.Paste")
			(net "P0V9_CPU0_RT0_2A_2D")
		)
		(pad "2" smd rect
			(at -0.2667 0 90)
			(size 0.3048 0.381)
			(layers "B.Cu" "B.Mask" "B.Paste")
			(net "GND")
		)
	)
	(footprint ""
		(layer "B.Cu")
		(at 83.51901 -390.560052 90)
		(property "Reference" "C321"
			(at 0 0 90)
			(layer "B.SilkS")
			(hide yes)
			(effects
				(font
					(size 1.27 1.27)
				)
				(justify mirror)
			)
		)
		(property "Value" ""
			(at 0 0 90)
			(layer "B.Fab")
			(effects
				(font
					(size 1.27 1.27)
				)
				(justify mirror)
			)
		)
		(duplicate_pad_numbers_are_jumpers no)
		(fp_line
			(start 0.7874 -0.4064)
			(end -0.7874 -0.4064)
			(stroke
				(width 0.1524)
				(type default)
			)
			(layer "B.SilkS")
		)
		(fp_line
			(start -0.7874 -0.4064)
			(end -0.7874 0.4064)
			(stroke
				(width 0.1524)
				(type default)
			)
			(layer "B.SilkS")
		)
		(fp_line
			(start 0.7874 0.4064)
			(end 0.7874 -0.4064)
			(stroke
				(width 0.1524)
				(type default)
			)
			(layer "B.SilkS")
		)
		(fp_line
			(start -0.7874 0.4064)
			(end 0.7874 0.4064)
			(stroke
				(width 0.1524)
				(type default)
			)
			(layer "B.SilkS")
		)
		(fp_line
			(start 0.67945 -0.305054)
			(end 0.12065 -0.305054)
			(stroke
				(width 0.1)
				(type default)
			)
			(layer "B.Fab")
		)
		(fp_line
			(start 0.12065 -0.305054)
			(end 0.12065 -0.2794)
			(stroke
				(width 0.1)
				(type default)
			)
			(layer "B.Fab")
		)
		(fp_line
			(start -0.12065 -0.3048)
			(end -0.67945 -0.3048)
			(stroke
				(width 0.1)
				(type default)
			)
			(layer "B.Fab")
		)
		(fp_line
			(start -0.67945 -0.3048)
			(end -0.67945 0.3048)
			(stroke
				(width 0.1)
				(type default)
			)
			(layer "B.Fab")
		)
		(fp_line
			(start 0.12065 -0.2794)
			(end -0.12065 -0.2794)
			(stroke
				(width 0.1)
				(type default)
			)
			(layer "B.Fab")
		)
		(fp_line
			(start -0.12065 -0.2794)
			(end -0.12065 -0.3048)
			(stroke
				(width 0.1)
				(type default)
			)
			(layer "B.Fab")
		)
		(fp_line
			(start 0.12065 0.2794)
			(end 0.12065 0.3048)
			(stroke
				(width 0.1)
				(type default)
			)
			(layer "B.Fab")
		)
		(fp_line
			(start -0.120396 0.2794)
			(end 0.12065 0.2794)
			(stroke
				(width 0.1)
				(type default)
			)
			(layer "B.Fab")
		)
		(fp_line
			(start 0.67945 0.3048)
			(end 0.67945 -0.305054)
			(stroke
				(width 0.1)
				(type default)
			)
			(layer "B.Fab")
		)
		(fp_line
			(start 0.12065 0.3048)
			(end 0.67945 0.3048)
			(stroke
				(width 0.1)
				(type default)
			)
			(layer "B.Fab")
		)
		(fp_line
			(start -0.120396 0.3048)
			(end -0.120396 0.2794)
			(stroke
				(width 0.1)
				(type default)
			)
			(layer "B.Fab")
		)
		(fp_line
			(start -0.67945 0.3048)
			(end -0.120396 0.3048)
			(stroke
				(width 0.1)
				(type default)
			)
			(layer "B.Fab")
		)
		(pad "1" smd circle
			(at 0.40005 0 270)
			(size 0 0)
			(layers "B.Cu" "B.Mask" "B.Paste")
			(net "P0V9_CPU1_RT1_2A")
		)
		(pad "2" smd circle
			(at -0.40005 0 270)
			(size 0 0)
			(layers "B.Cu" "B.Mask" "B.Paste")
			(net "GND")
		)
	)
)
